# T6G (Grand Teton) — schematic netlist excerpt (pin names and nets, part order shuffled) for the footprints in the layout excerpt that follows; sources: Cadence DE-HDL packaged netlist, KiCad conversion of 04192023_DAF0TMB3IC0_F0TG_MB_C_brd_V02_OCP.brd

PU38  ISL99390FRZTR5935  ISL99390FRZ-TR5935 IC  pkg QFN21_6X5XB  page 220
  VOS  = PVDDCR_CPU1_P1_VOS5
  AGND  = GND
  VCC  = PVDDCR_CPU1_P1_VCC5
  PVCC  = PVDDCR_CPU1_P1_PVCC
  PGND1  = GND
  GL1  = NC_PVDDCR_CPU1_P1_GL1_5
  PGND2  = GND
  SW  = SW_PVDDCR_CPU1_P1_SW5
  VIN1  = SW_P12V_AUX_PVDDCR_CPU1_P1_FLT
  VIN2  = SW_P12V_AUX_PVDDCR_CPU1_P1_FLT
  DNC  = NC_PVDDCR_CPU1_P1_DNC5
  PHASE  = SW_PVDDCR_CPU1_P1_BOOTR5
  BOOT  = SW_PVDDCR_CPU1_P1_BOOT5
  PWM  = PVDDCR_CPU1_P1_PWM5
  EN  = PVDDCR_CPU1_P1_VCC5
  TOUT_FLT  = PVDDCR_CPU1_P1_TEMP0
  LSET  = PVDDCR_CPU1_P1_LSET5
  IOUT  = PVDDCR_CPU1_P1_IMON5
  REFIN  = PVDDCR_CPU1_P1_VCCS
  PGND3  = GND
  GL2  = NC_PVDDCR_CPU1_P1_GL2_5

(kicad_pcb
	(version 20260206)
	(generator "pcbnew")
	(generator_version "10.0")
	(general
		(thickness 1.6)
		(legacy_teardrops no)
	)
	(paper "A4")
	(title_block
		(title "04192023_DAF0TMB3IC0_F0TG_MB_C_brd_V02_OCP.brd")
		(comment 1 "Grand Teton / footprints 2606-2606 of 8354")
	)
	(layers
		(0 "F.Cu" signal "TOP")
		(4 "In1.Cu" signal "GND")
		(6 "In2.Cu" signal "IN1")
		(8 "In3.Cu" signal "GND1")
		(10 "In4.Cu" signal "IN2")
		(12 "In5.Cu" signal "GND2")
		(14 "In6.Cu" signal "IN3")
		(16 "In7.Cu" signal "GND3")
		(18 "In8.Cu" signal "VCC")
		(20 "In9.Cu" signal "VCC1")
		(22 "In10.Cu" signal "GND4")
		(24 "In11.Cu" signal "IN4")
		(26 "In12.Cu" signal "GND5")
		(28 "In13.Cu" signal "IN5")
		(30 "In14.Cu" signal "GND6")
		(32 "In15.Cu" signal "IN6")
		(34 "In16.Cu" signal "GND7")
		(2 "B.Cu" signal "BOTTOM")
		(9 "F.Adhes" user "F.Adhesive")
		(11 "B.Adhes" user "B.Adhesive")
		(13 "F.Paste" user "Package Geometry/Pastemask Top")
		(15 "B.Paste" user "Package Geometry/Pastemask Bottom")
		(5 "F.SilkS" user "Ref Des/Silkscreen Top")
		(7 "B.SilkS" user "Ref Des/Silkscreen Bottom")
		(1 "F.Mask" user "Board Geometry/Soldermask Top")
		(3 "B.Mask" user "Board Geometry/Soldermask Bottom")
		(17 "Dwgs.User" user "User.Drawings")
		(19 "Cmts.User" user "User.Comments")
		(21 "Eco1.User" user "User.Eco1")
		(23 "Eco2.User" user "User.Eco2")
		(25 "Edge.Cuts" user "Board Geometry/Outline")
		(27 "Margin" user)
		(31 "F.CrtYd" user "Package Geometry/Place Bound Top")
		(29 "B.CrtYd" user "Package Geometry/Place Bound Bottom")
		(35 "F.Fab" user "Ref Des/Assembly Top")
		(33 "B.Fab" user "Ref Des/Assembly Bottom")
	)
	(footprint ""
		(layer "F.Cu")
		(at 95.453454 -335.029302)
		(property "Reference" "PU38"
			(at -2.616454 -8.479028 0)
			(unlocked yes)
			(layer "F.SilkS")
			(effects
				(font
					(size 0.7874 0.5842)
					(thickness 0.1524)
				)
				(justify left)
			)
		)
		(property "Value" ""
			(at 0 0 0)
			(layer "F.Fab")
			(effects
				(font
					(size 1.27 1.27)
				)
			)
		)
		(duplicate_pad_numbers_are_jumpers no)
		(fp_line
			(start -2.500122 -2.999994)
			(end -2.24409 -2.999994)
			(stroke
				(width 0.1524)
				(type default)
			)
			(layer "F.SilkS")
		)
		(fp_line
			(start -2.500122 -2.529078)
			(end -2.500122 -2.999994)
			(stroke
				(width 0.1524)
				(type default)
			)
			(layer "F.SilkS")
		)
		(fp_line
			(start -2.500122 0.6604)
			(end -2.500122 0.229108)
			(stroke
				(width 0.1524)
				(type default)
			)
			(layer "F.SilkS")
		)
		(fp_line
			(start -2.500122 2.999994)
			(end -2.500122 2.339594)
			(stroke
				(width 0.1524)
				(type default)
			)
			(layer "F.SilkS")
		)
		(fp_line
			(start -2.2987 2.999994)
			(end -2.500122 2.999994)
			(stroke
				(width 0.1524)
				(type default)
			)
			(layer "F.SilkS")
		)
		(fp_line
			(start 2.31394 -2.999994)
			(end 2.500122 -2.999994)
			(stroke
				(width 0.1524)
				(type default)
			)
			(layer "F.SilkS")
		)
		(fp_line
			(start 2.500122 -2.999994)
			(end 2.500122 -2.44348)
			(stroke
				(width 0.1524)
				(type default)
			)
			(layer "F.SilkS")
		)
		(fp_line
			(start 2.500122 2.339594)
			(end 2.500122 2.999994)
			(stroke
				(width 0.1524)
				(type default)
			)
			(layer "F.SilkS")
		)
		(fp_line
			(start 2.500122 2.999994)
			(end 2.2987 2.999994)
			(stroke
				(width 0.1524)
				(type default)
			)
			(layer "F.SilkS")
		)
		(fp_poly
			(pts
				(xy -2.742184 -2.419096) (xy -3.415538 -2.643632) (xy -2.966466 -3.092704)
			)
			(stroke
				(width 0)
				(type default)
			)
			(fill yes)
			(layer "F.SilkS")
		)
		(fp_line
			(start -2.500122 -2.999994)
			(end 2.500122 -2.999994)
			(stroke
				(width 0.1)
				(type default)
			)
			(layer "F.Fab")
		)
		(fp_line
			(start -2.500122 2.999994)
			(end -2.500122 -2.999994)
			(stroke
				(width 0.1)
				(type default)
			)
			(layer "F.Fab")
		)
		(fp_line
			(start 2.500122 -2.999994)
			(end 2.500122 2.999994)
			(stroke
				(width 0.1)
				(type default)
			)
			(layer "F.Fab")
		)
		(fp_line
			(start 2.500122 2.999994)
			(end -2.500122 2.999994)
			(stroke
				(width 0.1)
				(type default)
			)
			(layer "F.Fab")
		)
		(fp_poly
			(pts
				(xy -4.218432 -2.783078) (xy -4.218432 -1.767078) (xy -3.202432 -2.275078)
			)
			(stroke
				(width 0)
				(type default)
			)
			(fill yes)
			(layer "F.Fab")
		)
		(pad "1" smd rect
			(at -2.400046 -2.275078 90)
			(size 0.2286 0.6096)
			(layers "F.Cu" "F.Mask" "F.Paste")
			(net "PVDDCR_CPU1_P1_VOS5")
		)
		(pad "2" smd rect
			(at -2.400046 -1.82499 90)
			(size 0.2286 0.6096)
			(layers "F.Cu" "F.Mask" "F.Paste")
			(net "GND")
		)
		(pad "3" smd rect
			(at -2.400046 -1.374902 90)
			(size 0.2286 0.6096)
			(layers "F.Cu" "F.Mask" "F.Paste")
			(net "PVDDCR_CPU1_P1_VCC5")
		)
		(pad "4" smd rect
			(at -2.400046 -0.925068 90)
			(size 0.2286 0.6096)
			(layers "F.Cu" "F.Mask" "F.Paste")
			(net "PVDDCR_CPU1_P1_PVCC")
		)
		(pad "5" smd rect
			(at -2.400046 -0.47498 90)
			(size 0.2286 0.6096)
			(layers "F.Cu" "F.Mask" "F.Paste")
			(net "GND")
		)
		(pad "6" smd rect
			(at -2.400046 -0.024892 90)
			(size 0.2286 0.6096)
			(layers "F.Cu" "F.Mask" "F.Paste")
			(net "NC_PVDDCR_CPU1_P1_GL1_5")
		)
		(pad "7_9-20_24" smd circle
			(at 0 1.150112 90)
			(size 0 0)
			(layers "F.Cu" "F.Mask" "F.Paste")
			(net "GND")
		)
		(pad "10_19" smd rect
			(at 0 2.899918 90)
			(size 0.6096 4.318)
			(layers "F.Cu" "F.Mask" "F.Paste")
			(net "SW_PVDDCR_CPU1_P1_SW5")
		)
		(pad "25_29" smd rect
			(at 1.549908 -1.279906 270)
			(size 2.0574 2.3114)
			(layers "F.Cu" "F.Mask" "F.Paste")
			(net "SW_P12V_AUX_PVDDCR_CPU1_P1_FLT")
		)
		(pad "30" smd rect
			(at 2.05994 -2.899918)
			(size 0.2286 0.6096)
			(layers "F.Cu" "F.Mask" "F.Paste")
			(net "SW_P12V_AUX_PVDDCR_CPU1_P1_FLT")
		)
		(pad "31" smd rect
			(at 1.610106 -2.899918)
			(size 0.2286 0.6096)
			(layers "F.Cu" "F.Mask" "F.Paste")
			(net "NC_PVDDCR_CPU1_P1_DNC5")
		)
		(pad "32" smd rect
			(at 1.160018 -2.899918)
			(size 0.2286 0.6096)
			(layers "F.Cu" "F.Mask" "F.Paste")
			(net "SW_PVDDCR_CPU1_P1_BOOTR5")
		)
		(pad "33" smd rect
			(at 0.70993 -2.899918)
			(size 0.2286 0.6096)
			(layers "F.Cu" "F.Mask" "F.Paste")
			(net "SW_PVDDCR_CPU1_P1_BOOT5")
		)
		(pad "34" smd rect
			(at 0.260096 -2.899918)
			(size 0.2286 0.6096)
			(layers "F.Cu" "F.Mask" "F.Paste")
			(net "PVDDCR_CPU1_P1_PWM5")
		)
		(pad "35" smd rect
			(at -0.189992 -2.899918)
			(size 0.2286 0.6096)
			(layers "F.Cu" "F.Mask" "F.Paste")
			(net "PVDDCR_CPU1_P1_VCC5")
		)
		(pad "36" smd rect
			(at -0.64008 -2.899918)
			(size 0.2286 0.6096)
			(layers "F.Cu" "F.Mask" "F.Paste")
			(net "PVDDCR_CPU1_P1_TEMP0")
		)
		(pad "37" smd rect
			(at -1.089914 -2.899918)
			(size 0.2286 0.6096)
			(layers "F.Cu" "F.Mask" "F.Paste")
			(net "PVDDCR_CPU1_P1_LSET5")
		)
		(pad "38" smd rect
			(at -1.540002 -2.899918)
			(size 0.2286 0.6096)
			(layers "F.Cu" "F.Mask" "F.Paste")
			(net "PVDDCR_CPU1_P1_IMON5")
		)
		(pad "39" smd rect
			(at -1.99009 -2.899918)
			(size 0.2286 0.6096)
			(layers "F.Cu" "F.Mask" "F.Paste")
			(net "PVDDCR_CPU1_P1_VCCS")
		)
		(pad "40" smd rect
			(at -0.87503 -1.27508)
			(size 1.7526 1.9558)
			(layers "F.Cu" "F.Mask" "F.Paste")
			(net "GND")
		)
		(pad "41" smd rect
			(at -1.525016 0.249936 270)
			(size 0.3048 0.4572)
			(layers "F.Cu" "F.Mask" "F.Paste")
			(net "NC_PVDDCR_CPU1_P1_GL2_5")
		)
		(zone
			(layer "F.Cu")
			(hatch none 0.5)
			(connect_pads
				(clearance 0)
			)
			(min_thickness 0.25)
			(keepout
				(tracks not_allowed)
				(vias allowed)
				(pads allowed)
				(copperpour not_allowed)
				(footprints allowed)
			)
			(placement
				(enabled no)
				(sheetname "")
			)
			(fill
				(thermal_gap 0.5)
				(thermal_bridge_width 0.5)
				(island_removal_mode 0)
			)
			(polygon
				(pts
					(xy 92.953332 -332.450694) (xy 92.953332 -332.778608) (xy 97.953576 -332.778608) (xy 97.953576 -332.455774)
					(xy 97.663254 -332.455774) (xy 97.663254 -332.484984) (xy 93.243654 -332.484984) (xy 93.243654 -332.450694)
				)
			)
		)
		(zone
			(layer "F.Cu")
			(hatch none 0.5)
			(connect_pads
				(clearance 0)
			)
			(min_thickness 0.25)
			(keepout
				(tracks not_allowed)
				(vias allowed)
				(pads allowed)
				(copperpour not_allowed)
				(footprints allowed)
			)
			(placement
				(enabled no)
				(sheetname "")
			)
			(fill
				(thermal_gap 0.5)
				(thermal_bridge_width 0.5)
				(island_removal_mode 0)
			)
			(polygon
				(pts
					(xy 95.505524 -335.275682) (xy 95.505524 -337.333082) (xy 93.651324 -337.333082) (xy 93.651324 -337.092036)
					(xy 93.409008 -337.092036) (xy 93.409008 -337.57362) (xy 97.152714 -337.57362) (xy 97.152714 -337.388708)
					(xy 95.796862 -337.388708) (xy 95.796862 -335.229708) (xy 97.953576 -335.229708) (xy 97.953576 -334.980026)
					(xy 95.80118 -334.980026)
				)
			)
		)
	)
)
